(kicad_pcb
	(version 20260206)
	(generator "pcbnew")
	(generator_version "10.0")
	(general
		(thickness 1.6)
		(legacy_teardrops no)
	)
	(paper "A4")
	(title_block
		(title "12092022_DA0F0TFB6D0_F0T_FAN_BOARD_MP5048_D_brd_v02_OCP.brd")
		(comment 1 "Grand Teton / footprints 751-753 of 924")
	)
	(layers
		(0 "F.Cu" signal "TOP")
		(4 "In1.Cu" signal "GND")
		(6 "In2.Cu" signal "IN1")
		(8 "In3.Cu" signal "IN2")
		(10 "In4.Cu" signal "GND1")
		(2 "B.Cu" signal "BOTTOM")
		(9 "F.Adhes" user "F.Adhesive")
		(11 "B.Adhes" user "B.Adhesive")
		(13 "F.Paste" user "Package Geometry/Pastemask Top")
		(15 "B.Paste" user "Package Geometry/Pastemask Bottom")
		(5 "F.SilkS" user "Ref Des/Silkscreen Top")
		(7 "B.SilkS" user "Ref Des/Silkscreen Bottom")
		(1 "F.Mask" user "Board Geometry/Soldermask Top")
		(3 "B.Mask" user "Board Geometry/Soldermask Bottom")
		(17 "Dwgs.User" user "User.Drawings")
		(19 "Cmts.User" user "User.Comments")
		(21 "Eco1.User" user "User.Eco1")
		(23 "Eco2.User" user "User.Eco2")
		(25 "Edge.Cuts" user "Board Geometry/Outline")
		(27 "Margin" user)
		(31 "F.CrtYd" user "Package Geometry/Place Bound Top")
		(29 "B.CrtYd" user "Package Geometry/Place Bound Bottom")
		(35 "F.Fab" user "Ref Des/Assembly Top")
		(33 "B.Fab" user "Ref Des/Assembly Bottom")
	)
	(footprint ""
		(layer "B.Cu")
		(at 5.900166 -58.995056)
		(property "Reference" "PU6"
			(at 5.275834 2.252726 0)
			(unlocked yes)
			(layer "B.SilkS")
			(effects
				(font
					(size 0.7874 0.5842)
					(thickness 0.1524)
				)
				(justify left mirror)
			)
		)
		(property "Value" ""
			(at 0 0 0)
			(layer "B.Fab")
			(effects
				(font
					(size 1.27 1.27)
				)
				(justify mirror)
			)
		)
		(duplicate_pad_numbers_are_jumpers no)
		(fp_line
			(start -2.549906 -2.549906)
			(end -2.4384 -2.549906)
			(stroke
				(width 0.1524)
				(type default)
			)
			(layer "B.SilkS")
		)
		(fp_line
			(start -2.549906 -2.2352)
			(end -2.549906 -2.549906)
			(stroke
				(width 0.1524)
				(type default)
			)
			(layer "B.SilkS")
		)
		(fp_line
			(start -2.549906 -1.4986)
			(end -2.549906 -1.7526)
			(stroke
				(width 0.1524)
				(type default)
			)
			(layer "B.SilkS")
		)
		(fp_line
			(start -2.549906 -0.6858)
			(end -2.549906 -0.9144)
			(stroke
				(width 0.1524)
				(type default)
			)
			(layer "B.SilkS")
		)
		(fp_line
			(start -2.549906 0.9144)
			(end -2.549906 -0.1016)
			(stroke
				(width 0.1524)
				(type default)
			)
			(layer "B.SilkS")
		)
		(fp_line
			(start -2.549906 1.7526)
			(end -2.549906 1.4986)
			(stroke
				(width 0.1524)
				(type default)
			)
			(layer "B.SilkS")
		)
		(fp_line
			(start -2.549906 2.549906)
			(end -2.549906 2.2352)
			(stroke
				(width 0.1524)
				(type default)
			)
			(layer "B.SilkS")
		)
		(fp_line
			(start -2.4384 2.549906)
			(end -2.549906 2.549906)
			(stroke
				(width 0.1524)
				(type default)
			)
			(layer "B.SilkS")
		)
		(fp_line
			(start -2.199894 2.9464)
			(end -2.199894 3.4544)
			(stroke
				(width 0.1524)
				(type default)
			)
			(layer "B.SilkS")
		)
		(fp_line
			(start -1.800098 -3.9624)
			(end -1.800098 -2.9464)
			(stroke
				(width 0.1524)
				(type default)
			)
			(layer "B.SilkS")
		)
		(fp_line
			(start -0.199898 2.9464)
			(end -0.199898 3.9624)
			(stroke
				(width 0.1524)
				(type default)
			)
			(layer "B.SilkS")
		)
		(fp_line
			(start 0.199898 -3.4544)
			(end 0.199898 -2.9464)
			(stroke
				(width 0.1524)
				(type default)
			)
			(layer "B.SilkS")
		)
		(fp_line
			(start 1.800098 2.9464)
			(end 1.800098 3.4544)
			(stroke
				(width 0.1524)
				(type default)
			)
			(layer "B.SilkS")
		)
		(fp_line
			(start 2.199894 -3.9624)
			(end 2.199894 -2.9464)
			(stroke
				(width 0.1524)
				(type default)
			)
			(layer "B.SilkS")
		)
		(fp_line
			(start 2.4384 -2.549906)
			(end 2.549906 -2.549906)
			(stroke
				(width 0.1524)
				(type default)
			)
			(layer "B.SilkS")
		)
		(fp_line
			(start 2.549906 -2.549906)
			(end 2.549906 -2.2352)
			(stroke
				(width 0.1524)
				(type default)
			)
			(layer "B.SilkS")
		)
		(fp_line
			(start 2.549906 -1.7526)
			(end 2.549906 -1.4986)
			(stroke
				(width 0.1524)
				(type default)
			)
			(layer "B.SilkS")
		)
		(fp_line
			(start 2.549906 -0.9144)
			(end 2.549906 0.1016)
			(stroke
				(width 0.1524)
				(type default)
			)
			(layer "B.SilkS")
		)
		(fp_line
			(start 2.549906 0.6858)
			(end 2.549906 0.9144)
			(stroke
				(width 0.1524)
				(type default)
			)
			(layer "B.SilkS")
		)
		(fp_line
			(start 2.549906 1.4986)
			(end 2.549906 1.7526)
			(stroke
				(width 0.1524)
				(type default)
			)
			(layer "B.SilkS")
		)
		(fp_line
			(start 2.549906 2.2352)
			(end 2.549906 2.549906)
			(stroke
				(width 0.1524)
				(type default)
			)
			(layer "B.SilkS")
		)
		(fp_line
			(start 2.549906 2.549906)
			(end 2.4384 2.549906)
			(stroke
				(width 0.1524)
				(type default)
			)
			(layer "B.SilkS")
		)
		(fp_poly
			(pts
				(xy 3.488944 -1.474978) (xy 2.939034 -1.199896) (xy 3.488944 -0.925068)
			)
			(stroke
				(width 0)
				(type default)
			)
			(fill yes)
			(layer "B.SilkS")
		)
		(fp_line
			(start -2.549906 -2.549906)
			(end 2.549906 -2.549906)
			(stroke
				(width 0.1)
				(type default)
			)
			(layer "B.Fab")
		)
		(fp_line
			(start -2.549906 2.549906)
			(end -2.549906 -2.549906)
			(stroke
				(width 0.1)
				(type default)
			)
			(layer "B.Fab")
		)
		(fp_line
			(start -2.199894 2.9464)
			(end -2.199894 3.4544)
			(stroke
				(width 0.1)
				(type default)
			)
			(layer "B.Fab")
		)
		(fp_line
			(start -1.800098 -3.9624)
			(end -1.800098 -2.9464)
			(stroke
				(width 0.1)
				(type default)
			)
			(layer "B.Fab")
		)
		(fp_line
			(start -0.199898 2.9464)
			(end -0.199898 3.9624)
			(stroke
				(width 0.1)
				(type default)
			)
			(layer "B.Fab")
		)
		(fp_line
			(start 0.199898 -3.4544)
			(end 0.199898 -2.9464)
			(stroke
				(width 0.1)
				(type default)
			)
			(layer "B.Fab")
		)
		(fp_line
			(start 1.800098 2.9464)
			(end 1.800098 3.4544)
			(stroke
				(width 0.1)
				(type default)
			)
			(layer "B.Fab")
		)
		(fp_line
			(start 2.199894 -3.9624)
			(end 2.199894 -2.9464)
			(stroke
				(width 0.1)
				(type default)
			)
			(layer "B.Fab")
		)
		(fp_line
			(start 2.549906 -2.549906)
			(end 2.549906 2.549906)
			(stroke
				(width 0.1)
				(type default)
			)
			(layer "B.Fab")
		)
		(fp_line
			(start 2.549906 2.549906)
			(end -2.549906 2.549906)
			(stroke
				(width 0.1)
				(type default)
			)
			(layer "B.Fab")
		)
		(fp_poly
			(pts
				(xy 3.7084 -1.584706) (xy 2.939034 -1.199896) (xy 3.7084 -0.81534)
			)
			(stroke
				(width 0)
				(type default)
			)
			(fill yes)
			(layer "B.Fab")
		)
		(fp_text user "16"
			(at -3.329432 1.2192 270)
			(unlocked yes)
			(layer "B.SilkS")
			(effects
				(font
					(size 0.635 0.4064)
					(thickness 0.1524)
				)
				(justify mirror)
			)
		)
		(fp_text user "18"
			(at -3.304032 -1.2192 270)
			(unlocked yes)
			(layer "B.SilkS")
			(effects
				(font
					(size 0.635 0.4064)
					(thickness 0.1524)
				)
				(justify mirror)
			)
		)
		(fp_text user "15"
			(at -2.8956 3.126232 0)
			(unlocked yes)
			(layer "B.SilkS")
			(effects
				(font
					(size 0.635 0.4064)
					(thickness 0.1524)
				)
				(justify mirror)
			)
		)
		(fp_text user "19"
			(at -2.8448 -3.096768 0)
			(unlocked yes)
			(layer "B.SilkS")
			(effects
				(font
					(size 0.635 0.4064)
					(thickness 0.1524)
				)
				(justify mirror)
			)
		)
		(fp_text user "4"
			(at 2.6416 3.151632 0)
			(unlocked yes)
			(layer "B.SilkS")
			(effects
				(font
					(size 0.635 0.4064)
					(thickness 0.1524)
				)
				(justify mirror)
			)
		)
		(fp_text user "30"
			(at 2.9464 -3.045968 0)
			(unlocked yes)
			(layer "B.SilkS")
			(effects
				(font
					(size 0.635 0.4064)
					(thickness 0.1524)
				)
				(justify mirror)
			)
		)
		(fp_text user "3"
			(at 3.299968 1.1938 270)
			(unlocked yes)
			(layer "B.SilkS")
			(effects
				(font
					(size 0.635 0.4064)
					(thickness 0.1524)
				)
				(justify mirror)
			)
		)
		(fp_text user "16"
			(at -3.329432 1.2192 270)
			(unlocked yes)
			(layer "B.Fab")
			(effects
				(font
					(size 0.635 0.4064)
					(thickness 0.1524)
				)
				(justify mirror)
			)
		)
		(fp_text user "18"
			(at -3.304032 -1.2192 270)
			(unlocked yes)
			(layer "B.Fab")
			(effects
				(font
					(size 0.635 0.4064)
					(thickness 0.1524)
				)
				(justify mirror)
			)
		)
		(fp_text user "15"
			(at -2.8956 3.126232 0)
			(unlocked yes)
			(layer "B.Fab")
			(effects
				(font
					(size 0.635 0.4064)
					(thickness 0.1524)
				)
				(justify mirror)
			)
		)
		(fp_text user "19"
			(at -2.8448 -3.096768 0)
			(unlocked yes)
			(layer "B.Fab")
			(effects
				(font
					(size 0.635 0.4064)
					(thickness 0.1524)
				)
				(justify mirror)
			)
		)
		(fp_text user "4"
			(at 2.6416 3.151632 0)
			(unlocked yes)
			(layer "B.Fab")
			(effects
				(font
					(size 0.635 0.4064)
					(thickness 0.1524)
				)
				(justify mirror)
			)
		)
		(fp_text user "30"
			(at 2.9464 -3.045968 0)
			(unlocked yes)
			(layer "B.Fab")
			(effects
				(font
					(size 0.635 0.4064)
					(thickness 0.1524)
				)
				(justify mirror)
			)
		)
		(fp_text user "3"
			(at 3.299968 1.1938 270)
			(unlocked yes)
			(layer "B.Fab")
			(effects
				(font
					(size 0.635 0.4064)
					(thickness 0.1524)
				)
				(justify mirror)
			)
		)
		(pad "1" smd circle
			(at 1.599946 -1.199896 270)
			(size 0 0)
			(layers "B.Cu" "B.Mask" "B.Paste")
			(net "P52V_HSC")
		)
		(pad "2" smd rect
			(at 1.549908 0.40005 90)
			(size 0.3048 2.5146)
			(layers "B.Cu" "B.Mask" "B.Paste")
			(net "P52V_HSC")
		)
		(pad "3" smd rect
			(at 1.549908 1.199896 90)
			(size 0.3048 2.5146)
			(layers "B.Cu" "B.Mask" "B.Paste")
			(net "P52V_FAN_4")
		)
		(pad "4" smd circle
			(at 2.199894 2.350008)
			(size 0 0)
			(layers "B.Cu" "B.Mask" "B.Paste")
			(net "P52V_FAN_4")
		)
		(pad "5" smd rect
			(at 1.800098 2.350008 180)
			(size 0.1778 0.9144)
			(layers "B.Cu" "B.Mask" "B.Paste")
			(net "P52V_FAN_4")
		)
		(pad "6" smd rect
			(at 1.400048 2.350008 180)
			(size 0.1778 0.9144)
			(layers "B.Cu" "B.Mask" "B.Paste")
			(net "P52V_FAN_4")
		)
		(pad "7" smd rect
			(at 0.999998 2.350008 180)
			(size 0.1778 0.9144)
			(layers "B.Cu" "B.Mask" "B.Paste")
			(net "P52V_FAN_4")
		)
		(pad "8" smd rect
			(at 0.599948 2.350008 180)
			(size 0.1778 0.9144)
			(layers "B.Cu" "B.Mask" "B.Paste")
			(net "P52V_FAN_4")
		)
		(pad "9" smd rect
			(at 0.199898 2.350008 180)
			(size 0.1778 0.9144)
			(layers "B.Cu" "B.Mask" "B.Paste")
			(net "P52V_FAN_4")
		)
		(pad "10" smd rect
			(at -0.199898 2.350008 180)
			(size 0.1778 0.9144)
			(layers "B.Cu" "B.Mask" "B.Paste")
			(net "P52V_FAN_4")
		)
		(pad "11" smd rect
			(at -0.599948 2.350008 180)
			(size 0.1778 0.9144)
			(layers "B.Cu" "B.Mask" "B.Paste")
			(net "P52V_FAN_4")
		)
		(pad "12" smd rect
			(at -0.999998 2.350008 180)
			(size 0.1778 0.9144)
			(layers "B.Cu" "B.Mask" "B.Paste")
			(net "P52V_FAN_4")
		)
		(pad "13" smd rect
			(at -1.400048 2.350008 180)
			(size 0.1778 0.9144)
			(layers "B.Cu" "B.Mask" "B.Paste")
			(net "P52V_FAN_4")
		)
		(pad "14" smd rect
			(at -1.800098 2.350008 180)
			(size 0.1778 0.9144)
			(layers "B.Cu" "B.Mask" "B.Paste")
			(net "P52V_FAN_4")
		)
		(pad "15" smd circle
			(at -2.199894 2.350008)
			(size 0 0)
			(layers "B.Cu" "B.Mask" "B.Paste")
			(net "P52V_FAN_4")
		)
		(pad "16" smd rect
			(at -1.549908 1.199896 90)
			(size 0.3048 2.5146)
			(layers "B.Cu" "B.Mask" "B.Paste")
			(net "P52V_FAN_4")
		)
		(pad "17" smd rect
			(at -1.549908 -0.40005 90)
			(size 0.3048 2.5146)
			(layers "B.Cu" "B.Mask" "B.Paste")
			(net "P52V_FAN_4")
		)
		(pad "18" smd rect
			(at -1.549908 -1.199896 90)
			(size 0.3048 2.5146)
			(layers "B.Cu" "B.Mask" "B.Paste")
			(net "P52V_HSC")
		)
		(pad "19" smd circle
			(at -2.199894 -2.350008 180)
			(size 0 0)
			(layers "B.Cu" "B.Mask" "B.Paste")
			(net "FAN_4_CS")
		)
		(pad "20" smd rect
			(at -1.800098 -2.350008 180)
			(size 0.1778 0.9144)
			(layers "B.Cu" "B.Mask" "B.Paste")
			(net "FAN_4_IMON")
		)
		(pad "21" smd rect
			(at -1.400048 -2.350008 180)
			(size 0.1778 0.9144)
			(layers "B.Cu" "B.Mask" "B.Paste")
			(net "FAN_4_SS")
		)
		(pad "22" smd rect
			(at -0.999998 -2.350008 180)
			(size 0.1778 0.9144)
			(layers "B.Cu" "B.Mask" "B.Paste")
			(net "FAN_4_FAULT")
		)
		(pad "23" smd rect
			(at -0.599948 -2.350008 180)
			(size 0.1778 0.9144)
			(layers "B.Cu" "B.Mask" "B.Paste")
			(net "FAN_4_TIMER")
		)
		(pad "24" smd rect
			(at -0.199898 -2.350008 180)
			(size 0.1778 0.9144)
			(layers "B.Cu" "B.Mask" "B.Paste")
			(net "FAN_4_CLREF")
		)
		(pad "25" smd rect
			(at 0.199898 -2.350008 180)
			(size 0.1778 0.9144)
			(layers "B.Cu" "B.Mask" "B.Paste")
			(net "GND")
		)
		(pad "26" smd rect
			(at 0.599948 -2.350008 180)
			(size 0.1778 0.9144)
			(layers "B.Cu" "B.Mask" "B.Paste")
			(net "FAN_4_ON")
		)
		(pad "27" smd rect
			(at 0.999998 -2.350008 180)
			(size 0.1778 0.9144)
			(layers "B.Cu" "B.Mask" "B.Paste")
			(net "FAN_4_P3V_R")
		)
		(pad "28" smd rect
			(at 1.400048 -2.350008 180)
			(size 0.1778 0.9144)
			(layers "B.Cu" "B.Mask" "B.Paste")
			(net "FAN_4_P5V")
		)
		(pad "29" smd rect
			(at 1.800098 -2.350008 180)
			(size 0.1778 0.9144)
			(layers "B.Cu" "B.Mask" "B.Paste")
			(net "FAN_4_TEMP")
		)
		(pad "30" smd circle
			(at 2.199894 -2.350008 180)
			(size 0 0)
			(layers "B.Cu" "B.Mask" "B.Paste")
			(net "FAN_4_MODE")
		)
	)
	(footprint ""
		(layer "B.Cu")
		(at 33.142428 -78.416912 -90)
		(property "Reference" "PD6"
			(at 4.756912 3.959098 270)
			(unlocked yes)
			(layer "B.SilkS")
			(effects
				(font
					(size 0.7874 0.5842)
					(thickness 0.1524)
				)
				(justify left mirror)
			)
		)
		(property "Value" ""
			(at 0 0 90)
			(layer "B.Fab")
			(effects
				(font
					(size 1.27 1.27)
				)
				(justify mirror)
			)
		)
		(duplicate_pad_numbers_are_jumpers no)
		(fp_line
			(start -5.536184 3.109976)
			(end -5.536184 -3.109976)
			(stroke
				(width 0.1524)
				(type default)
			)
			(layer "B.SilkS")
		)
		(fp_line
			(start 4.647184 3.109976)
			(end -5.536184 3.109976)
			(stroke
				(width 0.1524)
				(type default)
			)
			(layer "B.SilkS")
		)
		(fp_line
			(start 0.635 0.635)
			(end -0.635 -0.127)
			(stroke
				(width 0.1524)
				(type default)
			)
			(layer "B.SilkS")
		)
		(fp_line
			(start -0.635 -0.127)
			(end -1.397 -0.127)
			(stroke
				(width 0.1524)
				(type default)
			)
			(layer "B.SilkS")
		)
		(fp_line
			(start -0.635 -0.127)
			(end 0.635 -0.889)
			(stroke
				(width 0.1524)
				(type default)
			)
			(layer "B.SilkS")
		)
		(fp_line
			(start 1.397 -0.127)
			(end 0.635 -0.127)
			(stroke
				(width 0.1524)
				(type default)
			)
			(layer "B.SilkS")
		)
		(fp_line
			(start 0.635 -0.889)
			(end 0.635 0.635)
			(stroke
				(width 0.1524)
				(type default)
			)
			(layer "B.SilkS")
		)
		(fp_line
			(start -0.762 -1.143)
			(end -0.762 0.889)
			(stroke
				(width 0.1524)
				(type default)
			)
			(layer "B.SilkS")
		)
		(fp_line
			(start -5.536184 -3.109976)
			(end 4.647184 -3.109976)
			(stroke
				(width 0.1524)
				(type default)
			)
			(layer "B.SilkS")
		)
		(fp_line
			(start 4.647184 -3.109976)
			(end 4.647184 3.109976)
			(stroke
				(width 0.1524)
				(type default)
			)
			(layer "B.SilkS")
		)
		(fp_poly
			(pts
				(xy -5.5118 -3.0988) (xy -5.5118 3.1496) (xy -4.572 3.1496) (xy -4.572 -3.0988)
			)
			(stroke
				(width 0)
				(type default)
			)
			(fill yes)
			(layer "B.SilkS")
		)
		(fp_line
			(start -3.554984 3.109976)
			(end -3.554984 -3.109976)
			(stroke
				(width 0.1)
				(type default)
			)
			(layer "B.Fab")
		)
		(fp_line
			(start 3.554984 3.109976)
			(end -3.554984 3.109976)
			(stroke
				(width 0.1)
				(type default)
			)
			(layer "B.Fab")
		)
		(fp_line
			(start -3.554984 -3.109976)
			(end 3.554984 -3.109976)
			(stroke
				(width 0.1)
				(type default)
			)
			(layer "B.Fab")
		)
		(fp_line
			(start 3.554984 -3.109976)
			(end 3.554984 3.109976)
			(stroke
				(width 0.1)
				(type default)
			)
			(layer "B.Fab")
		)
		(fp_text user "-"
			(at -5.334 -0.34925 270)
			(unlocked yes)
			(layer "B.SilkS")
			(effects
				(font
					(size 1.905 1.4224)
					(thickness 0.1524)
				)
				(justify left mirror)
			)
		)
		(fp_text user "+"
			(at 7.169912 -0.607822 270)
			(unlocked yes)
			(layer "B.SilkS")
			(effects
				(font
					(size 1.905 1.4224)
					(thickness 0.1524)
				)
				(justify left mirror)
			)
		)
		(fp_text user "+"
			(at 6.1214 -0.32385 270)
			(unlocked yes)
			(layer "B.Fab")
			(effects
				(font
					(size 1.905 1.4224)
					(thickness 0.1524)
				)
				(justify left mirror)
			)
		)
		(fp_text user "-"
			(at -5.334 -0.34925 270)
			(unlocked yes)
			(layer "B.Fab")
			(effects
				(font
					(size 1.905 1.4224)
					(thickness 0.1524)
				)
				(justify left mirror)
			)
		)
		(pad "A" smd rect
			(at 3.299968 0 90)
			(size 2.413 3.302)
			(layers "B.Cu" "B.Mask" "B.Paste")
			(net "GND")
		)
		(pad "C" smd rect
			(at -3.299968 0 90)
			(size 2.413 3.302)
			(layers "B.Cu" "B.Mask" "B.Paste")
			(net "P52V_HSC")
		)
	)
	(footprint ""
		(layer "B.Cu")
		(at 17.653 -129.667 180)
		(property "Reference" "R5437"
			(at 0 0 0)
			(layer "B.SilkS")
			(hide yes)
			(effects
				(font
					(size 1.27 1.27)
				)
				(justify mirror)
			)
		)
		(property "Value" ""
			(at 0 0 0)
			(layer "B.Fab")
			(effects
				(font
					(size 1.27 1.27)
				)
				(justify mirror)
			)
		)
		(duplicate_pad_numbers_are_jumpers no)
		(fp_line
			(start 0.7874 0.4064)
			(end 0.7874 -0.4064)
			(stroke
				(width 0.1524)
				(type default)
			)
			(layer "B.SilkS")
		)
		(fp_line
			(start 0.7874 -0.4064)
			(end -0.7874 -0.4064)
			(stroke
				(width 0.1524)
				(type default)
			)
			(layer "B.SilkS")
		)
		(fp_line
			(start -0.7874 0.4064)
			(end 0.7874 0.4064)
			(stroke
				(width 0.1524)
				(type default)
			)
			(layer "B.SilkS")
		)
		(fp_line
			(start -0.7874 -0.4064)
			(end -0.7874 0.4064)
			(stroke
				(width 0.1524)
				(type default)
			)
			(layer "B.SilkS")
		)
		(fp_line
			(start 0.67945 0.3048)
			(end 0.67945 -0.305054)
			(stroke
				(width 0.1)
				(type default)
			)
			(layer "B.Fab")
		)
		(fp_line
			(start 0.67945 -0.305054)
			(end 0.12065 -0.305054)
			(stroke
				(width 0.1)
				(type default)
			)
			(layer "B.Fab")
		)
		(fp_line
			(start 0.12065 0.3048)
			(end 0.67945 0.3048)
			(stroke
				(width 0.1)
				(type default)
			)
			(layer "B.Fab")
		)
		(fp_line
			(start 0.12065 0.2794)
			(end 0.12065 0.3048)
			(stroke
				(width 0.1)
				(type default)
			)
			(layer "B.Fab")
		)
		(fp_line
			(start 0.12065 -0.2794)
			(end -0.12065 -0.2794)
			(stroke
				(width 0.1)
				(type default)
			)
			(layer "B.Fab")
		)
		(fp_line
			(start 0.12065 -0.305054)
			(end 0.12065 -0.2794)
			(stroke
				(width 0.1)
				(type default)
			)
			(layer "B.Fab")
		)
		(fp_line
			(start -0.120396 0.3048)
			(end -0.120396 0.2794)
			(stroke
				(width 0.1)
				(type default)
			)
			(layer "B.Fab")
		)
		(fp_line
			(start -0.120396 0.2794)
			(end 0.12065 0.2794)
			(stroke
				(width 0.1)
				(type default)
			)
			(layer "B.Fab")
		)
		(fp_line
			(start -0.12065 -0.2794)
			(end -0.12065 -0.3048)
			(stroke
				(width 0.1)
				(type default)
			)
			(layer "B.Fab")
		)
		(fp_line
			(start -0.12065 -0.3048)
			(end -0.67945 -0.3048)
			(stroke
				(width 0.1)
				(type default)
			)
			(layer "B.Fab")
		)
		(fp_line
			(start -0.67945 0.3048)
			(end -0.120396 0.3048)
			(stroke
				(width 0.1)
				(type default)
			)
			(layer "B.Fab")
		)
		(fp_line
			(start -0.67945 -0.3048)
			(end -0.67945 0.3048)
			(stroke
				(width 0.1)
				(type default)
			)
			(layer "B.Fab")
		)
		(pad "1" smd rect
			(at 0.40005 0 180)
			(size 0.4572 0.508)
			(layers "B.Cu" "B.Mask" "B.Paste")
			(net "FAN_5_TACH_OL")
		)
		(pad "2" smd rect
			(at -0.40005 0 180)
			(size 0.4572 0.508)
			(layers "B.Cu" "B.Mask" "B.Paste")
			(net "GND")
		)
	)
)
